# SCM (Grand Teton) — schematic netlist excerpt (pin names and nets, part order shuffled) for the footprints in the layout excerpt that follows; sources: Cadence DE-HDL packaged netlist, KiCad conversion of 12092022_DA0F0TMDCD0_F0T_Management_Board_D_brd_V3_OCP.brd

R166  Q_RES  33.2 1% CHIP  pkg 0402LF  page 13 : A = IRQ_BMC_CPU_NMI_R ; B = IRQ_BMC_CPU_NMI
C273  Q_CAP  1UF 16V 10% EMPTY  pkg 0402  page 17 : A = LPC_ESPI_SEL_R ; B = GND

(kicad_pcb
	(version 20260206)
	(generator "pcbnew")
	(generator_version "10.0")
	(general
		(thickness 1.6)
		(legacy_teardrops no)
	)
	(paper "A4")
	(title_block
		(title "12092022_DA0F0TMDCD0_F0T_Management_Board_D_brd_V3_OCP.brd")
		(comment 1 "Grand Teton / footprints 753-754 of 1440")
	)
	(layers
		(0 "F.Cu" signal "TOP")
		(4 "In1.Cu" signal "GND")
		(6 "In2.Cu" signal "IN1")
		(8 "In3.Cu" signal "GND1")
		(10 "In4.Cu" signal "IN2")
		(12 "In5.Cu" signal "VCC")
		(14 "In6.Cu" signal "VCC1")
		(16 "In7.Cu" signal "IN3")
		(18 "In8.Cu" signal "GND2")
		(20 "In9.Cu" signal "IN4")
		(22 "In10.Cu" signal "GND3")
		(2 "B.Cu" signal "BOTTOM")
		(9 "F.Adhes" user "F.Adhesive")
		(11 "B.Adhes" user "B.Adhesive")
		(13 "F.Paste" user "Package Geometry/Pastemask Top")
		(15 "B.Paste" user "Package Geometry/Pastemask Bottom")
		(5 "F.SilkS" user "Ref Des/Silkscreen Top")
		(7 "B.SilkS" user "Ref Des/Silkscreen Bottom")
		(1 "F.Mask" user "Board Geometry/Soldermask Top")
		(3 "B.Mask" user "Board Geometry/Soldermask Bottom")
		(17 "Dwgs.User" user "User.Drawings")
		(19 "Cmts.User" user "User.Comments")
		(21 "Eco1.User" user "User.Eco1")
		(23 "Eco2.User" user "User.Eco2")
		(25 "Edge.Cuts" user "Board Geometry/Outline")
		(27 "Margin" user)
		(31 "F.CrtYd" user "Package Geometry/Place Bound Top")
		(29 "B.CrtYd" user "Package Geometry/Place Bound Bottom")
		(35 "F.Fab" user "Ref Des/Assembly Top")
		(33 "B.Fab" user "Ref Des/Assembly Bottom")
	)
	(footprint ""
		(layer "B.Cu")
		(at 77.2795 -100.935028)
		(property "Reference" "C273"
			(at 0 0 0)
			(layer "B.SilkS")
			(hide yes)
			(effects
				(font
					(size 1.27 1.27)
				)
				(justify mirror)
			)
		)
		(property "Value" ""
			(at 0 0 0)
			(layer "B.Fab")
			(effects
				(font
					(size 1.27 1.27)
				)
				(justify mirror)
			)
		)
		(duplicate_pad_numbers_are_jumpers no)
		(fp_line
			(start -0.7874 -0.4064)
			(end -0.7874 0.4064)
			(stroke
				(width 0.1524)
				(type default)
			)
			(layer "B.SilkS")
		)
		(fp_line
			(start -0.7874 0.4064)
			(end 0.7874 0.4064)
			(stroke
				(width 0.1524)
				(type default)
			)
			(layer "B.SilkS")
		)
		(fp_line
			(start 0.7874 -0.4064)
			(end -0.7874 -0.4064)
			(stroke
				(width 0.1524)
				(type default)
			)
			(layer "B.SilkS")
		)
		(fp_line
			(start 0.7874 0.4064)
			(end 0.7874 -0.4064)
			(stroke
				(width 0.1524)
				(type default)
			)
			(layer "B.SilkS")
		)
		(fp_line
			(start -0.67945 -0.3048)
			(end -0.67945 0.3048)
			(stroke
				(width 0.1)
				(type default)
			)
			(layer "B.Fab")
		)
		(fp_line
			(start -0.67945 0.3048)
			(end -0.120396 0.3048)
			(stroke
				(width 0.1)
				(type default)
			)
			(layer "B.Fab")
		)
		(fp_line
			(start -0.12065 -0.3048)
			(end -0.67945 -0.3048)
			(stroke
				(width 0.1)
				(type default)
			)
			(layer "B.Fab")
		)
		(fp_line
			(start -0.12065 -0.2794)
			(end -0.12065 -0.3048)
			(stroke
				(width 0.1)
				(type default)
			)
			(layer "B.Fab")
		)
		(fp_line
			(start -0.120396 0.2794)
			(end 0.12065 0.2794)
			(stroke
				(width 0.1)
				(type default)
			)
			(layer "B.Fab")
		)
		(fp_line
			(start -0.120396 0.3048)
			(end -0.120396 0.2794)
			(stroke
				(width 0.1)
				(type default)
			)
			(layer "B.Fab")
		)
		(fp_line
			(start 0.12065 -0.305054)
			(end 0.12065 -0.2794)
			(stroke
				(width 0.1)
				(type default)
			)
			(layer "B.Fab")
		)
		(fp_line
			(start 0.12065 -0.2794)
			(end -0.12065 -0.2794)
			(stroke
				(width 0.1)
				(type default)
			)
			(layer "B.Fab")
		)
		(fp_line
			(start 0.12065 0.2794)
			(end 0.12065 0.3048)
			(stroke
				(width 0.1)
				(type default)
			)
			(layer "B.Fab")
		)
		(fp_line
			(start 0.12065 0.3048)
			(end 0.67945 0.3048)
			(stroke
				(width 0.1)
				(type default)
			)
			(layer "B.Fab")
		)
		(fp_line
			(start 0.67945 -0.305054)
			(end 0.12065 -0.305054)
			(stroke
				(width 0.1)
				(type default)
			)
			(layer "B.Fab")
		)
		(fp_line
			(start 0.67945 0.3048)
			(end 0.67945 -0.305054)
			(stroke
				(width 0.1)
				(type default)
			)
			(layer "B.Fab")
		)
		(pad "1" smd circle
			(at 0.40005 0 180)
			(size 0 0)
			(layers "B.Cu" "B.Mask" "B.Paste")
			(net "LPC_ESPI_SEL_R")
		)
		(pad "2" smd circle
			(at -0.40005 0 180)
			(size 0 0)
			(layers "B.Cu" "B.Mask" "B.Paste")
			(net "GND")
		)
	)
	(footprint ""
		(layer "B.Cu")
		(at 41.966134 -44.92879 180)
		(property "Reference" "R166"
			(at 0 0 0)
			(layer "B.SilkS")
			(hide yes)
			(effects
				(font
					(size 1.27 1.27)
				)
				(justify mirror)
			)
		)
		(property "Value" ""
			(at 0 0 0)
			(layer "B.Fab")
			(effects
				(font
					(size 1.27 1.27)
				)
				(justify mirror)
			)
		)
		(duplicate_pad_numbers_are_jumpers no)
		(fp_line
			(start 0.7874 0.4064)
			(end 0.7874 -0.4064)
			(stroke
				(width 0.1524)
				(type default)
			)
			(layer "B.SilkS")
		)
		(fp_line
			(start 0.7874 -0.4064)
			(end -0.7874 -0.4064)
			(stroke
				(width 0.1524)
				(type default)
			)
			(layer "B.SilkS")
		)
		(fp_line
			(start -0.7874 0.4064)
			(end 0.7874 0.4064)
			(stroke
				(width 0.1524)
				(type default)
			)
			(layer "B.SilkS")
		)
		(fp_line
			(start -0.7874 -0.4064)
			(end -0.7874 0.4064)
			(stroke
				(width 0.1524)
				(type default)
			)
			(layer "B.SilkS")
		)
		(fp_line
			(start 0.67945 0.3048)
			(end 0.67945 -0.305054)
			(stroke
				(width 0.1)
				(type default)
			)
			(layer "B.Fab")
		)
		(fp_line
			(start 0.67945 -0.305054)
			(end 0.12065 -0.305054)
			(stroke
				(width 0.1)
				(type default)
			)
			(layer "B.Fab")
		)
		(fp_line
			(start 0.12065 0.3048)
			(end 0.67945 0.3048)
			(stroke
				(width 0.1)
				(type default)
			)
			(layer "B.Fab")
		)
		(fp_line
			(start 0.12065 0.2794)
			(end 0.12065 0.3048)
			(stroke
				(width 0.1)
				(type default)
			)
			(layer "B.Fab")
		)
		(fp_line
			(start 0.12065 -0.2794)
			(end -0.12065 -0.2794)
			(stroke
				(width 0.1)
				(type default)
			)
			(layer "B.Fab")
		)
		(fp_line
			(start 0.12065 -0.305054)
			(end 0.12065 -0.2794)
			(stroke
				(width 0.1)
				(type default)
			)
			(layer "B.Fab")
		)
		(fp_line
			(start -0.120396 0.3048)
			(end -0.120396 0.2794)
			(stroke
				(width 0.1)
				(type default)
			)
			(layer "B.Fab")
		)
		(fp_line
			(start -0.120396 0.2794)
			(end 0.12065 0.2794)
			(stroke
				(width 0.1)
				(type default)
			)
			(layer "B.Fab")
		)
		(fp_line
			(start -0.12065 -0.2794)
			(end -0.12065 -0.3048)
			(stroke
				(width 0.1)
				(type default)
			)
			(layer "B.Fab")
		)
		(fp_line
			(start -0.12065 -0.3048)
			(end -0.67945 -0.3048)
			(stroke
				(width 0.1)
				(type default)
			)
			(layer "B.Fab")
		)
		(fp_line
			(start -0.67945 0.3048)
			(end -0.120396 0.3048)
			(stroke
				(width 0.1)
				(type default)
			)
			(layer "B.Fab")
		)
		(fp_line
			(start -0.67945 -0.3048)
			(end -0.67945 0.3048)
			(stroke
				(width 0.1)
				(type default)
			)
			(layer "B.Fab")
		)
		(pad "1" smd circle
			(at 0.40005 0)
			(size 0 0)
			(layers "B.Cu" "B.Mask" "B.Paste")
			(net "IRQ_BMC_CPU_NMI_R")
		)
		(pad "2" smd circle
			(at -0.40005 0)
			(size 0 0)
			(layers "B.Cu" "B.Mask" "B.Paste")
			(net "IRQ_BMC_CPU_NMI")
		)
	)
)
